(kicad_pcb
	(version 20260206)
	(generator "pcbnew")
	(generator_version "10.0")
	(general
		(thickness 1.6)
		(legacy_teardrops no)
	)
	(paper "A4")
	(title_block
		(title "01162023_DA0F0TEBIF0_F0T_Expander_BD_F_brd_V02_OCP.brd")
		(comment 1 "Grand Teton / footprints 302-306 of 9728")
	)
	(layers
		(0 "F.Cu" signal "TOP")
		(4 "In1.Cu" signal "GND")
		(6 "In2.Cu" signal "VCC")
		(8 "In3.Cu" signal "VCC1")
		(10 "In4.Cu" signal "GND1")
		(12 "In5.Cu" signal "IN1")
		(14 "In6.Cu" signal "GND2")
		(16 "In7.Cu" signal "IN2")
		(18 "In8.Cu" signal "GND3")
		(20 "In9.Cu" signal "IN3")
		(22 "In10.Cu" signal "GND4")
		(24 "In11.Cu" signal "IN4")
		(26 "In12.Cu" signal "GND5")
		(28 "In13.Cu" signal "IN5")
		(30 "In14.Cu" signal "GND6")
		(32 "In15.Cu" signal "IN6")
		(34 "In16.Cu" signal "GND7")
		(2 "B.Cu" signal "BOTTOM")
		(9 "F.Adhes" user "F.Adhesive")
		(11 "B.Adhes" user "B.Adhesive")
		(13 "F.Paste" user "Package Geometry/Pastemask Top")
		(15 "B.Paste" user "Package Geometry/Pastemask Bottom")
		(5 "F.SilkS" user "Ref Des/Silkscreen Top")
		(7 "B.SilkS" user "Ref Des/Silkscreen Bottom")
		(1 "F.Mask" user "Board Geometry/Soldermask Top")
		(3 "B.Mask" user "Board Geometry/Soldermask Bottom")
		(17 "Dwgs.User" user "User.Drawings")
		(19 "Cmts.User" user "User.Comments")
		(21 "Eco1.User" user "User.Eco1")
		(23 "Eco2.User" user "User.Eco2")
		(25 "Edge.Cuts" user "Board Geometry/Outline")
		(27 "Margin" user)
		(31 "F.CrtYd" user "Package Geometry/Place Bound Top")
		(29 "B.CrtYd" user "Package Geometry/Place Bound Bottom")
		(35 "F.Fab" user "Ref Des/Assembly Top")
		(33 "B.Fab" user "Ref Des/Assembly Bottom")
	)
	(footprint ""
		(layer "F.Cu")
		(at 356.511098 -61.386974)
		(property "Reference" "R4499"
			(at 0 0 0)
			(layer "F.SilkS")
			(hide yes)
			(effects
				(font
					(size 1.27 1.27)
				)
			)
		)
		(property "Value" ""
			(at 0 0 0)
			(layer "F.Fab")
			(effects
				(font
					(size 1.27 1.27)
				)
			)
		)
		(duplicate_pad_numbers_are_jumpers no)
		(fp_line
			(start -0.7874 -0.4064)
			(end 0.7874 -0.4064)
			(stroke
				(width 0.1524)
				(type default)
			)
			(layer "F.SilkS")
		)
		(fp_line
			(start -0.7874 0.4064)
			(end -0.7874 -0.4064)
			(stroke
				(width 0.1524)
				(type default)
			)
			(layer "F.SilkS")
		)
		(fp_line
			(start 0.7874 -0.4064)
			(end 0.7874 0.4064)
			(stroke
				(width 0.1524)
				(type default)
			)
			(layer "F.SilkS")
		)
		(fp_line
			(start 0.7874 0.4064)
			(end -0.7874 0.4064)
			(stroke
				(width 0.1524)
				(type default)
			)
			(layer "F.SilkS")
		)
		(fp_line
			(start -0.67945 -0.305054)
			(end -0.12065 -0.305054)
			(stroke
				(width 0.1)
				(type default)
			)
			(layer "F.Fab")
		)
		(fp_line
			(start -0.67945 0.3048)
			(end -0.67945 -0.305054)
			(stroke
				(width 0.1)
				(type default)
			)
			(layer "F.Fab")
		)
		(fp_line
			(start -0.12065 -0.305054)
			(end -0.12065 -0.2794)
			(stroke
				(width 0.1)
				(type default)
			)
			(layer "F.Fab")
		)
		(fp_line
			(start -0.12065 -0.2794)
			(end 0.12065 -0.2794)
			(stroke
				(width 0.1)
				(type default)
			)
			(layer "F.Fab")
		)
		(fp_line
			(start -0.12065 0.2794)
			(end -0.12065 0.3048)
			(stroke
				(width 0.1)
				(type default)
			)
			(layer "F.Fab")
		)
		(fp_line
			(start -0.12065 0.3048)
			(end -0.67945 0.3048)
			(stroke
				(width 0.1)
				(type default)
			)
			(layer "F.Fab")
		)
		(fp_line
			(start 0.120396 0.2794)
			(end -0.12065 0.2794)
			(stroke
				(width 0.1)
				(type default)
			)
			(layer "F.Fab")
		)
		(fp_line
			(start 0.120396 0.3048)
			(end 0.120396 0.2794)
			(stroke
				(width 0.1)
				(type default)
			)
			(layer "F.Fab")
		)
		(fp_line
			(start 0.12065 -0.3048)
			(end 0.67945 -0.3048)
			(stroke
				(width 0.1)
				(type default)
			)
			(layer "F.Fab")
		)
		(fp_line
			(start 0.12065 -0.2794)
			(end 0.12065 -0.3048)
			(stroke
				(width 0.1)
				(type default)
			)
			(layer "F.Fab")
		)
		(fp_line
			(start 0.67945 -0.3048)
			(end 0.67945 0.3048)
			(stroke
				(width 0.1)
				(type default)
			)
			(layer "F.Fab")
		)
		(fp_line
			(start 0.67945 0.3048)
			(end 0.120396 0.3048)
			(stroke
				(width 0.1)
				(type default)
			)
			(layer "F.Fab")
		)
		(pad "1" smd circle
			(at -0.40005 0)
			(size 0 0)
			(layers "F.Cu" "F.Mask" "F.Paste")
			(net "PWRGD_P3V3_SSD12")
		)
		(pad "2" smd circle
			(at 0.40005 0)
			(size 0 0)
			(layers "F.Cu" "F.Mask" "F.Paste")
			(net "PWRGD_P3V3_SSD12_R")
		)
	)
	(footprint ""
		(layer "F.Cu")
		(at 162.61461 -66.32194 90)
		(property "Reference" "R5971"
			(at 0 0 90)
			(layer "F.SilkS")
			(hide yes)
			(effects
				(font
					(size 1.27 1.27)
				)
			)
		)
		(property "Value" ""
			(at 0 0 90)
			(layer "F.Fab")
			(effects
				(font
					(size 1.27 1.27)
				)
			)
		)
		(duplicate_pad_numbers_are_jumpers no)
		(fp_line
			(start 0.7874 -0.4064)
			(end 0.7874 0.4064)
			(stroke
				(width 0.1524)
				(type default)
			)
			(layer "F.SilkS")
		)
		(fp_line
			(start -0.7874 -0.4064)
			(end 0.7874 -0.4064)
			(stroke
				(width 0.1524)
				(type default)
			)
			(layer "F.SilkS")
		)
		(fp_line
			(start 0.7874 0.4064)
			(end -0.7874 0.4064)
			(stroke
				(width 0.1524)
				(type default)
			)
			(layer "F.SilkS")
		)
		(fp_line
			(start -0.7874 0.4064)
			(end -0.7874 -0.4064)
			(stroke
				(width 0.1524)
				(type default)
			)
			(layer "F.SilkS")
		)
		(fp_line
			(start -0.12065 -0.305054)
			(end -0.12065 -0.2794)
			(stroke
				(width 0.1)
				(type default)
			)
			(layer "F.Fab")
		)
		(fp_line
			(start -0.67945 -0.305054)
			(end -0.12065 -0.305054)
			(stroke
				(width 0.1)
				(type default)
			)
			(layer "F.Fab")
		)
		(fp_line
			(start 0.67945 -0.3048)
			(end 0.67945 0.3048)
			(stroke
				(width 0.1)
				(type default)
			)
			(layer "F.Fab")
		)
		(fp_line
			(start 0.12065 -0.3048)
			(end 0.67945 -0.3048)
			(stroke
				(width 0.1)
				(type default)
			)
			(layer "F.Fab")
		)
		(fp_line
			(start 0.12065 -0.2794)
			(end 0.12065 -0.3048)
			(stroke
				(width 0.1)
				(type default)
			)
			(layer "F.Fab")
		)
		(fp_line
			(start -0.12065 -0.2794)
			(end 0.12065 -0.2794)
			(stroke
				(width 0.1)
				(type default)
			)
			(layer "F.Fab")
		)
		(fp_line
			(start 0.120396 0.2794)
			(end -0.12065 0.2794)
			(stroke
				(width 0.1)
				(type default)
			)
			(layer "F.Fab")
		)
		(fp_line
			(start -0.12065 0.2794)
			(end -0.12065 0.3048)
			(stroke
				(width 0.1)
				(type default)
			)
			(layer "F.Fab")
		)
		(fp_line
			(start 0.67945 0.3048)
			(end 0.120396 0.3048)
			(stroke
				(width 0.1)
				(type default)
			)
			(layer "F.Fab")
		)
		(fp_line
			(start 0.120396 0.3048)
			(end 0.120396 0.2794)
			(stroke
				(width 0.1)
				(type default)
			)
			(layer "F.Fab")
		)
		(fp_line
			(start -0.12065 0.3048)
			(end -0.67945 0.3048)
			(stroke
				(width 0.1)
				(type default)
			)
			(layer "F.Fab")
		)
		(fp_line
			(start -0.67945 0.3048)
			(end -0.67945 -0.305054)
			(stroke
				(width 0.1)
				(type default)
			)
			(layer "F.Fab")
		)
		(pad "1" smd circle
			(at -0.40005 0 90)
			(size 0 0)
			(layers "F.Cu" "F.Mask" "F.Paste")
			(net "SSD5_PWR_EN_R")
		)
		(pad "2" smd circle
			(at 0.40005 0 90)
			(size 0 0)
			(layers "F.Cu" "F.Mask" "F.Paste")
			(net "P12V_SSD5_CO_EN")
		)
	)
	(footprint ""
		(layer "F.Cu")
		(at 22.84603 -46.4439 180)
		(property "Reference" "U51"
			(at 0.24003 -2.40157 0)
			(unlocked yes)
			(layer "F.SilkS")
			(effects
				(font
					(size 0.7874 0.5842)
					(thickness 0.1524)
				)
			)
		)
		(property "Value" ""
			(at 0 0 180)
			(layer "F.Fab")
			(effects
				(font
					(size 1.27 1.27)
				)
			)
		)
		(duplicate_pad_numbers_are_jumpers no)
		(fp_line
			(start 1.500124 1.500124)
			(end 1.004062 1.500124)
			(stroke
				(width 0.1524)
				(type default)
			)
			(layer "F.SilkS")
		)
		(fp_line
			(start 1.500124 1.004062)
			(end 1.500124 1.500124)
			(stroke
				(width 0.1524)
				(type default)
			)
			(layer "F.SilkS")
		)
		(fp_line
			(start 1.500124 -1.500124)
			(end 1.500124 -1.004062)
			(stroke
				(width 0.1524)
				(type default)
			)
			(layer "F.SilkS")
		)
		(fp_line
			(start 1.004062 -1.500124)
			(end 1.500124 -1.500124)
			(stroke
				(width 0.1524)
				(type default)
			)
			(layer "F.SilkS")
		)
		(fp_line
			(start -1.004062 1.500124)
			(end -1.500124 1.500124)
			(stroke
				(width 0.1524)
				(type default)
			)
			(layer "F.SilkS")
		)
		(fp_line
			(start -1.500124 1.500124)
			(end -1.500124 1.004062)
			(stroke
				(width 0.1524)
				(type default)
			)
			(layer "F.SilkS")
		)
		(fp_line
			(start -1.500124 -1.004062)
			(end -1.500124 -1.500124)
			(stroke
				(width 0.1524)
				(type default)
			)
			(layer "F.SilkS")
		)
		(fp_line
			(start -1.500124 -1.500124)
			(end -1.004062 -1.500124)
			(stroke
				(width 0.1524)
				(type default)
			)
			(layer "F.SilkS")
		)
		(fp_poly
			(pts
				(xy -1.947164 -2.341372) (xy -2.66573 -1.622806) (xy -1.588008 -1.26365)
			)
			(stroke
				(width 0)
				(type default)
			)
			(fill yes)
			(layer "F.SilkS")
		)
		(fp_line
			(start 1.500124 1.500124)
			(end -1.500124 1.500124)
			(stroke
				(width 0.1)
				(type default)
			)
			(layer "F.Fab")
		)
		(fp_line
			(start 1.500124 -1.500124)
			(end 1.500124 1.500124)
			(stroke
				(width 0.1)
				(type default)
			)
			(layer "F.Fab")
		)
		(fp_line
			(start -1.500124 1.500124)
			(end -1.500124 -1.500124)
			(stroke
				(width 0.1)
				(type default)
			)
			(layer "F.Fab")
		)
		(fp_line
			(start -1.500124 -1.500124)
			(end 1.500124 -1.500124)
			(stroke
				(width 0.1)
				(type default)
			)
			(layer "F.Fab")
		)
		(fp_poly
			(pts
				(xy -2.847848 -1.258062) (xy -2.847848 -0.242062) (xy -1.831848 -0.750062)
			)
			(stroke
				(width 0)
				(type default)
			)
			(fill yes)
			(layer "F.Fab")
		)
		(pad "1" smd rect
			(at -1.400048 -0.750062 90)
			(size 0.2286 0.6096)
			(layers "F.Cu" "F.Mask" "F.Paste")
			(net "SSD0_ADC_A1")
		)
		(pad "2" smd rect
			(at -1.400048 -0.249936 90)
			(size 0.2286 0.6096)
			(layers "F.Cu" "F.Mask" "F.Paste")
			(net "SSD0_ADC_A0")
		)
		(pad "3" smd rect
			(at -1.400048 0.249936 90)
			(size 0.2286 0.6096)
			(layers "F.Cu" "F.Mask" "F.Paste")
			(net "SSD0_ADC_ALERT_N")
		)
		(pad "4" smd rect
			(at -1.400048 0.750062 90)
			(size 0.2286 0.6096)
			(layers "F.Cu" "F.Mask" "F.Paste")
			(net "SMB_SSD0_ADC_SDA")
		)
		(pad "5" smd rect
			(at -0.750062 1.400048 180)
			(size 0.2286 0.6096)
			(layers "F.Cu" "F.Mask" "F.Paste")
			(net "SMB_SSD0_ADC_SCL")
		)
		(pad "6" smd rect
			(at -0.249936 1.400048 180)
			(size 0.2286 0.6096)
			(layers "F.Cu" "F.Mask" "F.Paste")
			(net "Net_4609")
		)
		(pad "7" smd rect
			(at 0.249936 1.400048 180)
			(size 0.2286 0.6096)
			(layers "F.Cu" "F.Mask" "F.Paste")
			(net "Net_4610")
		)
		(pad "8" smd rect
			(at 0.750062 1.400048 180)
			(size 0.2286 0.6096)
			(layers "F.Cu" "F.Mask" "F.Paste")
			(net "Net_4611")
		)
		(pad "9" smd rect
			(at 1.400048 0.750062 90)
			(size 0.2286 0.6096)
			(layers "F.Cu" "F.Mask" "F.Paste")
			(net "P3V3_AUX")
		)
		(pad "10" smd rect
			(at 1.400048 0.249936 90)
			(size 0.2286 0.6096)
			(layers "F.Cu" "F.Mask" "F.Paste")
			(net "GND")
		)
		(pad "11" smd rect
			(at 1.400048 -0.249936 90)
			(size 0.2286 0.6096)
			(layers "F.Cu" "F.Mask" "F.Paste")
			(net "P12V_SSD0_R")
		)
		(pad "12" smd rect
			(at 1.400048 -0.750062 90)
			(size 0.2286 0.6096)
			(layers "F.Cu" "F.Mask" "F.Paste")
			(net "P12V_SSD0_VIN_N")
		)
		(pad "13" smd rect
			(at 0.750062 -1.400048 180)
			(size 0.2286 0.6096)
			(layers "F.Cu" "F.Mask" "F.Paste")
			(net "P12V_SSD0_VIN_P")
		)
		(pad "14" smd rect
			(at 0.249936 -1.400048 180)
			(size 0.2286 0.6096)
			(layers "F.Cu" "F.Mask" "F.Paste")
			(net "Net_4612")
		)
		(pad "15" smd rect
			(at -0.249936 -1.400048 180)
			(size 0.2286 0.6096)
			(layers "F.Cu" "F.Mask" "F.Paste")
			(net "Net_4613")
		)
		(pad "16" smd rect
			(at -0.750062 -1.400048 180)
			(size 0.2286 0.6096)
			(layers "F.Cu" "F.Mask" "F.Paste")
			(net "Net_4614")
		)
		(pad "TH" smd rect
			(at 0 0 180)
			(size 1.7018 1.7018)
			(layers "F.Cu" "F.Mask" "F.Paste")
			(net "GND")
		)
		(zone
			(layer "F.Cu")
			(hatch none 0.5)
			(connect_pads
				(clearance 0)
			)
			(min_thickness 0.25)
			(keepout
				(tracks not_allowed)
				(vias allowed)
				(pads allowed)
				(copperpour not_allowed)
				(footprints allowed)
			)
			(placement
				(enabled no)
				(sheetname "")
			)
			(fill
				(thermal_gap 0.5)
				(thermal_bridge_width 0.5)
				(island_removal_mode 0)
			)
			(polygon
				(pts
					(xy 23.890478 -46.4185) (xy 23.890478 -45.399452) (xy 21.801582 -45.399452) (xy 21.801582 -47.488348)
					(xy 23.890478 -47.488348) (xy 23.890478 -46.4439) (xy 23.74773 -46.4439) (xy 23.74773 -47.3456)
					(xy 21.94433 -47.3456) (xy 21.94433 -45.5422) (xy 23.74773 -45.5422) (xy 23.74773 -46.4185)
				)
			)
		)
	)
	(footprint ""
		(layer "F.Cu")
		(at 363.474 -206.883)
		(property "Reference" "R4599"
			(at 0 0 0)
			(layer "F.SilkS")
			(hide yes)
			(effects
				(font
					(size 1.27 1.27)
				)
			)
		)
		(property "Value" ""
			(at 0 0 0)
			(layer "F.Fab")
			(effects
				(font
					(size 1.27 1.27)
				)
			)
		)
		(duplicate_pad_numbers_are_jumpers no)
		(fp_line
			(start -0.7874 -0.4064)
			(end 0.7874 -0.4064)
			(stroke
				(width 0.1524)
				(type default)
			)
			(layer "F.SilkS")
		)
		(fp_line
			(start -0.7874 0.4064)
			(end -0.7874 -0.4064)
			(stroke
				(width 0.1524)
				(type default)
			)
			(layer "F.SilkS")
		)
		(fp_line
			(start 0.7874 -0.4064)
			(end 0.7874 0.4064)
			(stroke
				(width 0.1524)
				(type default)
			)
			(layer "F.SilkS")
		)
		(fp_line
			(start 0.7874 0.4064)
			(end -0.7874 0.4064)
			(stroke
				(width 0.1524)
				(type default)
			)
			(layer "F.SilkS")
		)
		(fp_line
			(start -0.67945 -0.305054)
			(end -0.12065 -0.305054)
			(stroke
				(width 0.1)
				(type default)
			)
			(layer "F.Fab")
		)
		(fp_line
			(start -0.67945 0.3048)
			(end -0.67945 -0.305054)
			(stroke
				(width 0.1)
				(type default)
			)
			(layer "F.Fab")
		)
		(fp_line
			(start -0.12065 -0.305054)
			(end -0.12065 -0.2794)
			(stroke
				(width 0.1)
				(type default)
			)
			(layer "F.Fab")
		)
		(fp_line
			(start -0.12065 -0.2794)
			(end 0.12065 -0.2794)
			(stroke
				(width 0.1)
				(type default)
			)
			(layer "F.Fab")
		)
		(fp_line
			(start -0.12065 0.2794)
			(end -0.12065 0.3048)
			(stroke
				(width 0.1)
				(type default)
			)
			(layer "F.Fab")
		)
		(fp_line
			(start -0.12065 0.3048)
			(end -0.67945 0.3048)
			(stroke
				(width 0.1)
				(type default)
			)
			(layer "F.Fab")
		)
		(fp_line
			(start 0.120396 0.2794)
			(end -0.12065 0.2794)
			(stroke
				(width 0.1)
				(type default)
			)
			(layer "F.Fab")
		)
		(fp_line
			(start 0.120396 0.3048)
			(end 0.120396 0.2794)
			(stroke
				(width 0.1)
				(type default)
			)
			(layer "F.Fab")
		)
		(fp_line
			(start 0.12065 -0.3048)
			(end 0.67945 -0.3048)
			(stroke
				(width 0.1)
				(type default)
			)
			(layer "F.Fab")
		)
		(fp_line
			(start 0.12065 -0.2794)
			(end 0.12065 -0.3048)
			(stroke
				(width 0.1)
				(type default)
			)
			(layer "F.Fab")
		)
		(fp_line
			(start 0.67945 -0.3048)
			(end 0.67945 0.3048)
			(stroke
				(width 0.1)
				(type default)
			)
			(layer "F.Fab")
		)
		(fp_line
			(start 0.67945 0.3048)
			(end 0.120396 0.3048)
			(stroke
				(width 0.1)
				(type default)
			)
			(layer "F.Fab")
		)
		(pad "1" smd circle
			(at -0.40005 0)
			(size 0 0)
			(layers "F.Cu" "F.Mask" "F.Paste")
			(net "P3V3_AUX")
		)
		(pad "2" smd circle
			(at 0.40005 0)
			(size 0 0)
			(layers "F.Cu" "F.Mask" "F.Paste")
			(net "SSD1_PEX_PWR_EN_R")
		)
	)
	(footprint ""
		(layer "F.Cu")
		(at 249.20575 -83.431888)
		(property "Reference" "R1062"
			(at 0 0 0)
			(layer "F.SilkS")
			(hide yes)
			(effects
				(font
					(size 1.27 1.27)
				)
			)
		)
		(property "Value" ""
			(at 0 0 0)
			(layer "F.Fab")
			(effects
				(font
					(size 1.27 1.27)
				)
			)
		)
		(duplicate_pad_numbers_are_jumpers no)
		(fp_line
			(start -0.7874 -0.4064)
			(end 0.7874 -0.4064)
			(stroke
				(width 0.1524)
				(type default)
			)
			(layer "F.SilkS")
		)
		(fp_line
			(start -0.7874 0.4064)
			(end -0.7874 -0.4064)
			(stroke
				(width 0.1524)
				(type default)
			)
			(layer "F.SilkS")
		)
		(fp_line
			(start 0.7874 -0.4064)
			(end 0.7874 0.4064)
			(stroke
				(width 0.1524)
				(type default)
			)
			(layer "F.SilkS")
		)
		(fp_line
			(start 0.7874 0.4064)
			(end -0.7874 0.4064)
			(stroke
				(width 0.1524)
				(type default)
			)
			(layer "F.SilkS")
		)
		(fp_line
			(start -0.67945 -0.305054)
			(end -0.12065 -0.305054)
			(stroke
				(width 0.1)
				(type default)
			)
			(layer "F.Fab")
		)
		(fp_line
			(start -0.67945 0.3048)
			(end -0.67945 -0.305054)
			(stroke
				(width 0.1)
				(type default)
			)
			(layer "F.Fab")
		)
		(fp_line
			(start -0.12065 -0.305054)
			(end -0.12065 -0.2794)
			(stroke
				(width 0.1)
				(type default)
			)
			(layer "F.Fab")
		)
		(fp_line
			(start -0.12065 -0.2794)
			(end 0.12065 -0.2794)
			(stroke
				(width 0.1)
				(type default)
			)
			(layer "F.Fab")
		)
		(fp_line
			(start -0.12065 0.2794)
			(end -0.12065 0.3048)
			(stroke
				(width 0.1)
				(type default)
			)
			(layer "F.Fab")
		)
		(fp_line
			(start -0.12065 0.3048)
			(end -0.67945 0.3048)
			(stroke
				(width 0.1)
				(type default)
			)
			(layer "F.Fab")
		)
		(fp_line
			(start 0.120396 0.2794)
			(end -0.12065 0.2794)
			(stroke
				(width 0.1)
				(type default)
			)
			(layer "F.Fab")
		)
		(fp_line
			(start 0.120396 0.3048)
			(end 0.120396 0.2794)
			(stroke
				(width 0.1)
				(type default)
			)
			(layer "F.Fab")
		)
		(fp_line
			(start 0.12065 -0.3048)
			(end 0.67945 -0.3048)
			(stroke
				(width 0.1)
				(type default)
			)
			(layer "F.Fab")
		)
		(fp_line
			(start 0.12065 -0.2794)
			(end 0.12065 -0.3048)
			(stroke
				(width 0.1)
				(type default)
			)
			(layer "F.Fab")
		)
		(fp_line
			(start 0.67945 -0.3048)
			(end 0.67945 0.3048)
			(stroke
				(width 0.1)
				(type default)
			)
			(layer "F.Fab")
		)
		(fp_line
			(start 0.67945 0.3048)
			(end 0.120396 0.3048)
			(stroke
				(width 0.1)
				(type default)
			)
			(layer "F.Fab")
		)
		(pad "1" smd circle
			(at -0.40005 0)
			(size 0 0)
			(layers "F.Cu" "F.Mask" "F.Paste")
			(net "GND")
		)
		(pad "2" smd circle
			(at 0.40005 0)
			(size 0 0)
			(layers "F.Cu" "F.Mask" "F.Paste")
			(net "CLK_CK440_SMB_ADDR0")
		)
	)
)
